(kicad_pcb
	(version 20260206)
	(generator "pcbnew")
	(generator_version "10.0")
	(general
		(thickness 1.6)
		(legacy_teardrops no)
	)
	(paper "A4")
	(title_block
		(title "Bryce Canyon_R.DPB_16317-1_OCP.brd")
		(comment 1 "Bryce Canyon / footprints 576-576 of 2099")
	)
	(layers
		(0 "F.Cu" signal "TOP")
		(4 "In1.Cu" signal "L2GND")
		(6 "In2.Cu" signal "L3")
		(8 "In3.Cu" signal "L4VCC")
		(10 "In4.Cu" signal "L5VCC")
		(12 "In5.Cu" signal "L6")
		(14 "In6.Cu" signal "L7GND")
		(2 "B.Cu" signal "BOTTOM")
		(9 "F.Adhes" user "F.Adhesive")
		(11 "B.Adhes" user "B.Adhesive")
		(13 "F.Paste" user "Package Geometry/Pastemask Top")
		(15 "B.Paste" user "Package Geometry/Pastemask Bottom")
		(5 "F.SilkS" user "Ref Des/Silkscreen Top")
		(7 "B.SilkS" user "Ref Des/Silkscreen Bottom")
		(1 "F.Mask" user "Board Geometry/Soldermask Top")
		(3 "B.Mask" user "Board Geometry/Soldermask Bottom")
		(17 "Dwgs.User" user "User.Drawings")
		(19 "Cmts.User" user "User.Comments")
		(21 "Eco1.User" user "User.Eco1")
		(23 "Eco2.User" user "User.Eco2")
		(25 "Edge.Cuts" user "Board Geometry/Outline")
		(27 "Margin" user)
		(31 "F.CrtYd" user "Package Geometry/Place Bound Top")
		(29 "B.CrtYd" user "Package Geometry/Place Bound Bottom")
		(35 "F.Fab" user "Ref Des/Assembly Top")
		(33 "B.Fab" user "Ref Des/Assembly Bottom")
	)
	(footprint ""
		(layer "F.Cu")
		(at 357.100124 -28.910026 -90)
		(property "Reference" "HDDSAS31"
			(at 0 0 270)
			(layer "F.SilkS")
			(hide yes)
			(effects
				(font
					(size 1.27 1.27)
				)
			)
		)
		(property "Value" "SKT-SAS15P-14P-45-GP"
			(at -20.7645 -8.9789 270)
			(unlocked yes)
			(layer "F.Fab")
			(hide yes)
			(effects
				(font
					(size 1.016 1.016)
					(thickness 0.1524)
				)
			)
		)
		(property "Device Type" "10120818-001C-TRLF"
			(at -20.7645 -10.5029 270)
			(unlocked yes)
			(layer "F.Fab")
			(hide yes)
			(effects
				(font
					(size 1.016 1.016)
					(thickness 0.1524)
				)
			)
		)
		(duplicate_pad_numbers_are_jumpers no)
		(fp_line
			(start 1.651 4.2926)
			(end 1.651 3.0099)
			(stroke
				(width 0.1524)
				(type default)
			)
			(layer "F.SilkS")
		)
		(fp_line
			(start 8.509 4.2926)
			(end 1.651 4.2926)
			(stroke
				(width 0.1524)
				(type default)
			)
			(layer "F.SilkS")
		)
		(fp_line
			(start -23.4188 3.0099)
			(end -23.4188 -3.2512)
			(stroke
				(width 0.1524)
				(type default)
			)
			(layer "F.SilkS")
		)
		(fp_line
			(start 1.651 3.0099)
			(end -23.4188 3.0099)
			(stroke
				(width 0.1524)
				(type default)
			)
			(layer "F.SilkS")
		)
		(fp_line
			(start 8.509 3.0099)
			(end 8.509 4.2926)
			(stroke
				(width 0.1524)
				(type default)
			)
			(layer "F.SilkS")
		)
		(fp_line
			(start 23.4188 3.0099)
			(end 8.509 3.0099)
			(stroke
				(width 0.1524)
				(type default)
			)
			(layer "F.SilkS")
		)
		(fp_line
			(start -23.4188 -3.2512)
			(end 23.4188 -3.2512)
			(stroke
				(width 0.1524)
				(type default)
			)
			(layer "F.SilkS")
		)
		(fp_line
			(start 23.4188 -3.2512)
			(end 23.4188 3.0099)
			(stroke
				(width 0.1524)
				(type default)
			)
			(layer "F.SilkS")
		)
		(fp_line
			(start 15.5067 -3.3401)
			(end 16.2687 -3.3401)
			(stroke
				(width 0.3302)
				(type default)
			)
			(layer "F.SilkS")
		)
		(fp_poly
			(pts
				(xy 15.868904 -3.230372) (xy 16.503904 -3.865372) (xy 15.233904 -3.865372)
			)
			(stroke
				(width 0)
				(type default)
			)
			(fill yes)
			(layer "F.SilkS")
		)
		(fp_poly
			(pts
				(xy -22.8727 -2.7559) (xy 22.8727 -2.7559) (xy 22.8727 2.7559) (xy 8.255 2.7559) (xy 8.255 3.5179)
				(xy 1.905 3.5179) (xy 1.905 2.7559) (xy -22.8727 2.7559)
			)
			(stroke
				(width 0)
				(type default)
			)
			(fill no)
			(layer "F.CrtYd")
		)
		(fp_poly
			(pts
				(xy 1.397 4.5466) (xy 1.397 3.2639) (xy -23.6728 3.2639) (xy -23.6728 -3.5052) (xy 23.6728 -3.5052)
				(xy 23.6728 -0.00635) (xy 22.8727 -0.00635) (xy 22.8727 -2.7559) (xy -22.8727 -2.7559) (xy -22.8727 2.7559)
				(xy 1.905 2.7559) (xy 1.905 3.5179) (xy 8.255 3.5179) (xy 8.255 2.7559) (xy 22.8727 2.7559) (xy 22.8727 0.00635)
				(xy 23.6728 0.00635) (xy 23.6728 3.2639) (xy 8.763 3.2639) (xy 8.763 4.5466)
			)
			(stroke
				(width 0)
				(type default)
			)
			(fill no)
			(layer "F.CrtYd")
		)
		(fp_poly
			(pts
				(xy 1.397 4.5466) (xy 1.397 3.2639) (xy -23.6728 3.2639) (xy -23.6728 -3.5052) (xy 23.6728 -3.5052)
				(xy 23.6728 3.2639) (xy 8.763 3.2639) (xy 8.763 4.5466)
			)
			(stroke
				(width 0)
				(type default)
			)
			(fill no)
			(layer "F.Fab")
		)
		(pad "" np_thru_hole circle
			(at -18.874994 0 270)
			(size 0.254 0.254)
			(drill 1.3462)
			(layers "*.Cu" "*.Mask")
			(clearance 0.9017)
			(thermal_gap 0.9017)
		)
		(pad "" np_thru_hole circle
			(at 18.874994 0 270)
			(size 0.254 0.254)
			(drill 0.9398)
			(layers "*.Cu" "*.Mask")
			(clearance 0.6985)
			(thermal_gap 0.6985)
		)
		(pad "G1" smd rect
			(at 21.874988 0 270)
			(size 2.5908 2.5908)
			(layers "F.Cu" "F.Mask" "F.Paste")
			(net "GND")
		)
		(pad "G2" smd rect
			(at -21.874988 0 270)
			(size 2.5908 2.5908)
			(layers "F.Cu" "F.Mask" "F.Paste")
			(net "GND")
		)
		(pad "P1" smd rect
			(at 1.905 -1.82499 270)
			(size 0.6096 2.3622)
			(layers "F.Cu" "F.Mask" "F.Paste")
			(net "Net_1639")
		)
		(pad "P2" smd rect
			(at 0.635 -1.82499 270)
			(size 0.6096 2.3622)
			(layers "F.Cu" "F.Mask" "F.Paste")
			(net "Net_1640")
		)
		(pad "P3" smd rect
			(at -0.635 -1.82499 270)
			(size 0.6096 2.3622)
			(layers "F.Cu" "F.Mask" "F.Paste")
			(net "Net_1641")
		)
		(pad "P4" smd rect
			(at -1.905 -1.82499 270)
			(size 0.6096 2.3622)
			(layers "F.Cu" "F.Mask" "F.Paste")
			(net "GND")
		)
		(pad "P5" smd rect
			(at -3.175 -1.82499 270)
			(size 0.6096 2.3622)
			(layers "F.Cu" "F.Mask" "F.Paste")
			(net "HDD_PRSNT_31")
		)
		(pad "P6" smd rect
			(at -4.445 -1.82499 270)
			(size 0.6096 2.3622)
			(layers "F.Cu" "F.Mask" "F.Paste")
			(net "GND")
		)
		(pad "P7" smd rect
			(at -5.715 -1.82499 270)
			(size 0.6096 2.3622)
			(layers "F.Cu" "F.Mask" "F.Paste")
			(net "5V_PRE_31")
		)
		(pad "P8" smd rect
			(at -6.985 -1.82499 270)
			(size 0.6096 2.3622)
			(layers "F.Cu" "F.Mask" "F.Paste")
			(net "P5V_HDD31")
		)
		(pad "P9" smd rect
			(at -8.255 -1.82499 270)
			(size 0.6096 2.3622)
			(layers "F.Cu" "F.Mask" "F.Paste")
			(net "P5V_HDD31")
		)
		(pad "P10" smd rect
			(at -9.525 -1.82499 270)
			(size 0.6096 2.3622)
			(layers "F.Cu" "F.Mask" "F.Paste")
			(net "GND")
		)
		(pad "P11" smd rect
			(at -10.795 -1.82499 270)
			(size 0.6096 2.3622)
			(layers "F.Cu" "F.Mask" "F.Paste")
			(net "ACT_HDD_31")
		)
		(pad "P12" smd rect
			(at -12.065 -1.82499 270)
			(size 0.6096 2.3622)
			(layers "F.Cu" "F.Mask" "F.Paste")
			(net "GND")
		)
		(pad "P13" smd rect
			(at -13.335 -1.82499 270)
			(size 0.6096 2.3622)
			(layers "F.Cu" "F.Mask" "F.Paste")
			(net "12V_PRE_31")
		)
		(pad "P14" smd rect
			(at -14.605 -1.82499 270)
			(size 0.6096 2.3622)
			(layers "F.Cu" "F.Mask" "F.Paste")
			(net "P12V_HDD31")
		)
		(pad "P15" smd rect
			(at -15.875 -1.82499 270)
			(size 0.6096 2.3622)
			(layers "F.Cu" "F.Mask" "F.Paste")
			(net "P12V_HDD31")
		)
		(pad "S1" smd rect
			(at 15.875 -1.82499 270)
			(size 0.6096 2.3622)
			(layers "F.Cu" "F.Mask" "F.Paste")
			(net "GND")
		)
		(pad "S2" smd rect
			(at 14.605 -1.82499 270)
			(size 0.6096 2.3622)
			(layers "F.Cu" "F.Mask" "F.Paste")
			(net "SAS_HDD_RX_P31")
		)
		(pad "S3" smd rect
			(at 13.335 -1.82499 270)
			(size 0.6096 2.3622)
			(layers "F.Cu" "F.Mask" "F.Paste")
			(net "SAS_HDD_RX_N31")
		)
		(pad "S4" smd rect
			(at 12.065 -1.82499 270)
			(size 0.6096 2.3622)
			(layers "F.Cu" "F.Mask" "F.Paste")
			(net "GND")
		)
		(pad "S5" smd rect
			(at 10.795 -1.82499 270)
			(size 0.6096 2.3622)
			(layers "F.Cu" "F.Mask" "F.Paste")
			(net "PHY_DRV_B_TO_SCC_B_31_DN")
		)
		(pad "S6" smd rect
			(at 9.525 -1.82499 270)
			(size 0.6096 2.3622)
			(layers "F.Cu" "F.Mask" "F.Paste")
			(net "PHY_DRV_B_TO_SCC_B_31_DP")
		)
		(pad "S7" smd rect
			(at 8.255 -1.82499 270)
			(size 0.6096 2.3622)
			(layers "F.Cu" "F.Mask" "F.Paste")
			(net "GND")
		)
		(pad "S8" smd rect
			(at 7.480046 2.845054 270)
			(size 0.508 2.3622)
			(layers "F.Cu" "F.Mask" "F.Paste")
			(net "GND")
		)
		(pad "S9" smd rect
			(at 6.679946 2.845054 270)
			(size 0.508 2.3622)
			(layers "F.Cu" "F.Mask" "F.Paste")
			(net "Net_456")
		)
		(pad "S10" smd rect
			(at 5.8801 2.845054 270)
			(size 0.508 2.3622)
			(layers "F.Cu" "F.Mask" "F.Paste")
			(net "Net_348")
		)
		(pad "S11" smd rect
			(at 5.08 2.845054 270)
			(size 0.508 2.3622)
			(layers "F.Cu" "F.Mask" "F.Paste")
			(net "GND")
		)
		(pad "S12" smd rect
			(at 4.2799 2.845054 270)
			(size 0.508 2.3622)
			(layers "F.Cu" "F.Mask" "F.Paste")
			(net "Net_384")
		)
		(pad "S13" smd rect
			(at 3.480054 2.845054 270)
			(size 0.508 2.3622)
			(layers "F.Cu" "F.Mask" "F.Paste")
			(net "Net_420")
		)
		(pad "S14" smd rect
			(at 2.679954 2.845054 270)
			(size 0.508 2.3622)
			(layers "F.Cu" "F.Mask" "F.Paste")
			(net "GND")
		)
		(zone
			(layer "F.Cu")
			(hatch none 0.5)
			(connect_pads
				(clearance 0)
			)
			(min_thickness 0.25)
			(keepout
				(tracks not_allowed)
				(vias allowed)
				(pads allowed)
				(copperpour not_allowed)
				(footprints allowed)
			)
			(placement
				(enabled no)
				(sheetname "")
			)
			(fill
				(thermal_gap 0.5)
				(thermal_bridge_width 0.5)
				(island_removal_mode 0)
			)
			(polygon
				(pts
					(xy 360.757724 -45.648626) (xy 353.683824 -45.648626) (xy 353.683824 -52.582826) (xy 354.788724 -52.582826)
					(xy 354.788724 -48.468026) (xy 359.411524 -48.468026) (xy 359.411524 -52.582826) (xy 360.757724 -52.582826)
				)
			)
		)
		(zone
			(layer "F.Cu")
			(hatch none 0.5)
			(connect_pads
				(clearance 0)
			)
			(min_thickness 0.25)
			(keepout
				(tracks allowed)
				(vias not_allowed)
				(pads allowed)
				(copperpour not_allowed)
				(footprints allowed)
			)
			(placement
				(enabled no)
				(sheetname "")
			)
			(fill
				(thermal_gap 0.5)
				(thermal_bridge_width 0.5)
				(island_removal_mode 0)
			)
			(polygon
				(pts
					(xy 360.757724 -45.648626) (xy 353.683824 -45.648626) (xy 353.683824 -52.582826) (xy 354.788724 -52.582826)
					(xy 354.788724 -48.468026) (xy 359.411524 -48.468026) (xy 359.411524 -52.582826) (xy 360.757724 -52.582826)
				)
			)
		)
		(zone
			(layer "F.Cu")
			(hatch none 0.5)
			(connect_pads
				(clearance 0)
			)
			(min_thickness 0.25)
			(keepout
				(tracks allowed)
				(vias not_allowed)
				(pads allowed)
				(copperpour not_allowed)
				(footprints allowed)
			)
			(placement
				(enabled no)
				(sheetname "")
			)
			(fill
				(thermal_gap 0.5)
				(thermal_bridge_width 0.5)
				(island_removal_mode 0)
			)
			(polygon
				(pts
					(xy 360.757724 -12.171426) (xy 353.683824 -12.171426) (xy 353.683824 -5.237226) (xy 354.788724 -5.237226)
					(xy 354.788724 -9.352026) (xy 359.411524 -9.352026) (xy 359.411524 -5.237226) (xy 360.757724 -5.237226)
				)
			)
		)
		(zone
			(layer "F.Cu")
			(hatch none 0.5)
			(connect_pads
				(clearance 0)
			)
			(min_thickness 0.25)
			(keepout
				(tracks not_allowed)
				(vias allowed)
				(pads allowed)
				(copperpour not_allowed)
				(footprints allowed)
			)
			(placement
				(enabled no)
				(sheetname "")
			)
			(fill
				(thermal_gap 0.5)
				(thermal_bridge_width 0.5)
				(island_removal_mode 0)
			)
			(polygon
				(pts
					(xy 360.757724 -12.171426) (xy 353.683824 -12.171426) (xy 353.683824 -5.237226) (xy 354.788724 -5.237226)
					(xy 354.788724 -9.352026) (xy 359.411524 -9.352026) (xy 359.411524 -5.237226) (xy 360.757724 -5.237226)
				)
			)
		)
		(zone
			(layers "F.Cu" "B.Cu" "In1.Cu" "In2.Cu" "In3.Cu" "In4.Cu" "In5.Cu" "In6.Cu")
			(hatch none 0.5)
			(connect_pads
				(clearance 0)
			)
			(min_thickness 0.25)
			(keepout
				(tracks not_allowed)
				(vias allowed)
				(pads allowed)
				(copperpour not_allowed)
				(footprints allowed)
			)
			(placement
				(enabled no)
				(sheetname "")
			)
			(fill
				(thermal_gap 0.5)
				(thermal_bridge_width 0.5)
				(island_removal_mode 0)
			)
			(polygon
				(pts
					(arc
						(start 357.874824 -10.035032)
						(mid 356.325424 -10.035032)
						(end 357.874824 -10.035032)
					)
				)
			)
		)
		(zone
			(layers "F.Cu" "B.Cu" "In1.Cu" "In2.Cu" "In3.Cu" "In4.Cu" "In5.Cu" "In6.Cu")
			(hatch none 0.5)
			(connect_pads
				(clearance 0)
			)
			(min_thickness 0.25)
			(keepout
				(tracks not_allowed)
				(vias allowed)
				(pads allowed)
				(copperpour not_allowed)
				(footprints allowed)
			)
			(placement
				(enabled no)
				(sheetname "")
			)
			(fill
				(thermal_gap 0.5)
				(thermal_bridge_width 0.5)
				(island_removal_mode 0)
			)
			(polygon
				(pts
					(arc
						(start 358.078024 -47.78502)
						(mid 356.122224 -47.78502)
						(end 358.078024 -47.78502)
					)
				)
			)
		)
	)
)
